G04 ================== begin FILE IDENTIFICATION RECORD ==================*
G04 Layout Name:  16368-sb.brd*
G04 Film Name:    TSILK*
G04 File Format:  Gerber RS274X*
G04 File Origin:  Cadence Allegro 16.5-S056*
G04 Origin Date:  Tue Feb 07 09:07:41 2017*
G04 *
G04 Layer:  VIA CLASS/FILMMASKTOP*
G04 Layer:  REF DES/ASSEMBLY_TOP*
G04 Layer:  PACKAGE GEOMETRY/SILKSCREEN_TOP*
G04 Layer:  DRAWING FORMAT/LAYER_PCB_STORY*
G04 Layer:  DRAWING FORMAT/LAYER_SILK_T*
G04 Layer:  BOARD GEOMETRY/SILKSCREEN_TOP*
G04 *
G04 Offset:    (0.00 0.00)*
G04 Mirror:    No*
G04 Mode:      Positive*
G04 Rotation:  0*
G04 FullContactRelief:  No*
G04 UndefLineWidth:     6.00*
G04 ================== end FILE IDENTIFICATION RECORD ====================*
%FSLAX35Y35*MOIN*%
%IR0*IPPOS*OFA0.00000B0.00000*MIA0B0*SFA1.00000B1.00000*%
%ADD10C,.01*%
%ADD11C,.02*%
%ADD12C,.012*%
%ADD13C,.013*%
%ADD14C,.006*%
G75*
%LPD*%
G75*
G54D10*
G01X88000Y56000D02*
X94000D01*
Y52000D01*
X109500D01*
G01X80000Y56000D02*
X72500D01*
Y61000D01*
G01X114000Y52000D02*
X125500D01*
G01X129500D02*
X143500D01*
Y60000D01*
G01X285349Y-19685D02*
G03X274877I-5236J0D01*
G01X253854D02*
G03X243381I-5236J0D01*
G01X222359D02*
G03X211886I-5237J0D01*
G01X348339D02*
G03X337867I-5236J0D01*
G01X316844D02*
G03X306372I-5236J0D01*
G01X379834D02*
G03X369362I-5236J0D01*
G54D11*
G01X-149983Y-76117D02*
Y-156117D01*
G01D02*
X864117D01*
G01X-153983Y-60117D02*
G02I-12000J0D01*
G01X-159133D02*
G02I-6850J0D01*
G01X-165983Y-76117D02*
Y-44117D01*
G01X-149983Y-60117D02*
X-181983D01*
G01X-149983Y-76117D02*
X864117D01*
G01X-149983Y-111617D02*
X864117D01*
G01X76617Y-76117D02*
Y-156117D01*
G01X123460Y5906D02*
Y293D01*
X112760D01*
Y5906D01*
G01X109287D02*
Y293D01*
X98587D01*
Y5906D01*
G01X95114D02*
Y293D01*
X84414D01*
Y5906D01*
G01X80941D02*
Y293D01*
X70241D01*
Y5906D01*
G01X66767D02*
Y293D01*
X56067D01*
Y5906D01*
G01X52594D02*
Y293D01*
X41894D01*
Y5906D01*
G01X76400Y46000D02*
Y52000D01*
G01X214117Y-76117D02*
Y-156117D01*
G01X329117Y-76117D02*
Y-156117D01*
G01X496617Y-76117D02*
Y-156117D01*
G01X666617Y-76117D02*
Y-156117D01*
G01X864117Y-76117D02*
Y-156117D01*
G01X892117Y-60117D02*
G02I-12000J0D01*
G01X886967D02*
G02I-6850J0D01*
G01X880117Y-76117D02*
Y-44117D01*
G01X896117Y-60117D02*
X864117D01*
G54D12*
G01X11811Y0D02*
X37008D01*
G01X11811Y69685D02*
X37008D01*
G01X11811Y61811D02*
X37008D01*
G01X28960Y54102D02*
G02X34811Y57750I3245J1312D01*
G01X32205Y34984D02*
G02X29041Y39981I0J3500D01*
G01X11811Y139370D02*
X37008D01*
G01X11811Y131496D02*
X37008D01*
G01X11811Y209055D02*
X37008D01*
G01X11811Y201181D02*
X37008D01*
G01X11811Y278740D02*
X37008D01*
G01X11811Y270866D02*
X37008D01*
G01X11811Y348425D02*
X37008D01*
G01X11811Y340551D02*
X37008D01*
G01Y418110D02*
X11811D01*
G01X37008Y410236D02*
X11811D01*
G01Y487795D02*
X37008D01*
G01X11811Y479921D02*
X37008D01*
G01X11811Y557480D02*
X37008D01*
G01X11811Y549606D02*
X37008D01*
G01X11811Y627165D02*
X37008D01*
G01X11811Y619291D02*
X37008D01*
G01X48474Y57725D02*
G02X54310Y54012I2629J-2311D01*
G01X54393Y39677D02*
G02X51103Y34984I-3290J-1193D01*
G01X185040Y43504D02*
Y18307D01*
G01X177166Y43504D02*
Y18307D01*
G01X140158Y0D02*
X165355D01*
G01X196851D02*
X222048D01*
G01X140158Y69685D02*
X165355D01*
G01X140158Y61811D02*
X165355D01*
G01X177166Y113189D02*
Y87992D01*
G01X185040Y113189D02*
Y87992D01*
G01X196851Y139370D02*
X222048D01*
G01X196851Y131496D02*
X222048D01*
G01X140158Y139370D02*
X165355D01*
G01X140158Y131496D02*
X165355D01*
G01X177166Y182874D02*
Y157677D01*
G01X185040Y182874D02*
Y157677D01*
G01X140158Y209055D02*
X165355D01*
G01X140158Y201181D02*
X165355D01*
G01X177166Y227362D02*
Y252559D01*
G01X185040Y227362D02*
Y252559D01*
G01X196851Y209055D02*
X222048D01*
G01X196851Y201181D02*
X222048D01*
G01X196851Y278740D02*
X222048D01*
G01X196851Y270866D02*
X222048D01*
G01X140158Y278740D02*
X165355D01*
G01X140158Y270866D02*
X165355D01*
G01X177166Y322244D02*
Y297047D01*
G01X185040Y322244D02*
Y297047D01*
G01X140158Y348425D02*
X165355D01*
G01X140158Y340551D02*
X165355D01*
G01X196851Y348425D02*
X222048D01*
G01X196851Y340551D02*
X222048D01*
G01X177166Y391929D02*
Y366732D01*
G01X185040Y391929D02*
Y366732D01*
G01X222048Y418110D02*
X196851D01*
G01X222048Y410236D02*
X196851D01*
G01X140158Y418110D02*
X165355D01*
G01X140158Y410236D02*
X165355D01*
G01X177166Y461614D02*
Y436417D01*
G01X185040Y461614D02*
Y436417D01*
G01X140158Y487795D02*
X165355D01*
G01X140158Y479921D02*
X165355D01*
G01X177166Y531299D02*
Y506102D01*
G01X185040Y531299D02*
Y506102D01*
G01X222048Y487795D02*
X196851D01*
G01X222048Y479921D02*
X196851D01*
G01X177166Y600984D02*
Y575787D01*
G01X185040Y600984D02*
Y575787D01*
G01X140158Y557480D02*
X165355D01*
G01X140158Y549606D02*
X165355D01*
G01X196851Y557480D02*
X222048D01*
G01X196851Y549606D02*
X222048D01*
G01X196851Y627165D02*
X222048D01*
G01X196851Y619291D02*
X222048D01*
G01X177166Y670669D02*
Y645472D01*
G01X185040Y670669D02*
Y645472D01*
G01X165355Y627165D02*
X140158D01*
G01X165355Y619291D02*
X140158D01*
G01X325197Y0D02*
X350394D01*
G01X362205Y43504D02*
Y18307D01*
G01X325197Y69685D02*
X350394D01*
G01X325197Y61811D02*
X350394D01*
G01X362205Y113189D02*
Y87992D01*
G01X325197Y139370D02*
X350394D01*
G01X325197Y131496D02*
X350394D01*
G01X362205Y182874D02*
Y157677D01*
G01X350394Y209055D02*
X325197D01*
G01X350394Y201181D02*
X325197D01*
G01X362205Y252559D02*
Y227362D01*
G01X325197Y278740D02*
X350394D01*
G01X325197Y270866D02*
X350394D01*
G01X362205Y322244D02*
Y297047D01*
G01X325197Y348425D02*
X350394D01*
G01X325197Y340551D02*
X350394D01*
G01X362205Y391929D02*
Y366732D01*
G01Y461614D02*
Y436417D01*
G01X325197Y418110D02*
X350394D01*
G01X325197Y410236D02*
X350394D01*
G01X325197Y487795D02*
X350394D01*
G01X325197Y479921D02*
X350394D01*
G01X362205Y531299D02*
Y506102D01*
G01Y600984D02*
Y575787D01*
G01X325197Y557480D02*
X350394D01*
G01X325197Y549606D02*
X350394D01*
G01X362205Y670669D02*
Y645472D01*
G01X350394Y627165D02*
X325197D01*
G01X350394Y619291D02*
X325197D01*
G01X370079Y43504D02*
Y18307D01*
G01X381890Y0D02*
X407087D01*
G01X381890Y69685D02*
X407087D01*
G01X381890Y61811D02*
X407087D01*
G01X370079Y113189D02*
Y87992D01*
G01X381890Y139370D02*
X407087D01*
G01X381890Y131496D02*
X407087D01*
G01X370079Y182874D02*
Y157677D01*
G01Y252559D02*
Y227362D01*
G01X381890Y209055D02*
X407087D01*
G01X381890Y201181D02*
X407087D01*
G01X381890Y278740D02*
X407087D01*
G01X381890Y270866D02*
X407087D01*
G01X370079Y322244D02*
Y297047D01*
G01X407087Y348425D02*
X381890D01*
G01X407087Y340551D02*
X381890D01*
G01X370079Y391929D02*
Y366732D01*
G01X381890Y418110D02*
X407087D01*
G01X381890Y410236D02*
X407087D01*
G01X370079Y461614D02*
Y436417D01*
G01X381890Y487795D02*
X407087D01*
G01X381890Y479921D02*
X407087D01*
G01X370079Y531299D02*
Y506102D01*
G01X407087Y557480D02*
X381890D01*
G01X407087Y549606D02*
X381890D01*
G01X370079Y600984D02*
Y575787D01*
G01X381890Y627165D02*
X407087D01*
G01X381890Y619291D02*
X407087D01*
G01X370079Y670669D02*
Y645472D01*
G01X510237Y0D02*
X535433D01*
G01X510237Y69685D02*
X535433D01*
G01X510237Y61811D02*
X535433D01*
G01X510237Y139370D02*
X535433D01*
G01X510237Y131496D02*
X535433D01*
G01X510237Y209055D02*
X535433D01*
G01X510237Y201181D02*
X535433D01*
G01X510237Y278740D02*
X535433D01*
G01X510237Y270866D02*
X535433D01*
G01Y348425D02*
X510237D01*
G01X535433Y340551D02*
X510237D01*
G01Y418110D02*
X535433D01*
G01X510237Y410236D02*
X535433D01*
G01X510237Y487795D02*
X535433D01*
G01X510237Y479921D02*
X535433D01*
G01X510237Y557480D02*
X535433D01*
G01X510237Y549606D02*
X535433D01*
G01X510237Y627165D02*
X535433D01*
G01X510237Y619291D02*
X535433D01*
G54D13*
G01X64900Y32100D02*
Y34950D01*
X67600D01*
G01X94100Y38600D02*
X96950D01*
Y35900D01*
G01X116100Y34100D02*
X118950D01*
Y31400D01*
G01X128100Y34100D02*
X130950D01*
Y31400D01*
G54D14*
G01X-137600Y-128617D02*
Y-146117D01*
X-128866D01*
G01X-113987Y-136784D02*
X-113113Y-135909D01*
X-112458Y-134451D01*
X-112021Y-132408D01*
X-112458Y-130659D01*
X-113331Y-129492D01*
X-114860Y-128617D01*
X-120755D01*
Y-146117D01*
X-113550D01*
X-112021Y-144951D01*
X-111148Y-143200D01*
X-110711Y-141159D01*
X-111148Y-139117D01*
X-112458Y-137367D01*
X-113987Y-136784D01*
X-120755D01*
G01X-93430Y-130076D02*
X-94740Y-129200D01*
X-96268Y-128617D01*
X-98015D01*
X-99980Y-129492D01*
X-101508Y-130950D01*
X-102600Y-132701D01*
X-103473Y-135617D01*
X-103692Y-138242D01*
X-103255Y-140867D01*
X-102600Y-142617D01*
X-101290Y-144367D01*
X-99761Y-145534D01*
X-98233Y-146117D01*
X-96705D01*
X-95176Y-145534D01*
X-93866Y-144659D01*
X-92774Y-143493D01*
G01X-67600Y-128617D02*
Y-146117D01*
X-58866D01*
G01X-41366D02*
X-50100D01*
Y-128617D01*
X-41366D01*
G01X-44860Y-137075D02*
X-50100D01*
G01X-33036Y-146117D02*
Y-128617D01*
X-28670D01*
X-26923Y-129492D01*
X-25613Y-130659D01*
X-24521Y-132408D01*
X-23648Y-134451D01*
X-23430Y-137367D01*
X-23648Y-140284D01*
X-24521Y-142326D01*
X-25613Y-144076D01*
X-26923Y-145242D01*
X-28670Y-146117D01*
X-33036D01*
G01X10260Y-135909D02*
X8732Y-134742D01*
X7422Y-134451D01*
X5675Y-135034D01*
X4365Y-136200D01*
X3492Y-138242D01*
X3273Y-140284D01*
X3492Y-142326D01*
X4365Y-144076D01*
X5675Y-145534D01*
X7422Y-146117D01*
X8950Y-145534D01*
X10260Y-144367D01*
G01X28197Y-146117D02*
Y-134451D01*
G01Y-136492D02*
X27324Y-135326D01*
X26013Y-134742D01*
X24485Y-134451D01*
X22957Y-135034D01*
X21647Y-136200D01*
X20773Y-137950D01*
X20337Y-140284D01*
X20773Y-142617D01*
X21647Y-144367D01*
X22957Y-145534D01*
X24485Y-146117D01*
X26013Y-145825D01*
X27324Y-144951D01*
X28197Y-143784D01*
G01X38710Y-146117D02*
Y-134451D01*
G01Y-136784D02*
X39802Y-135617D01*
X40894Y-134742D01*
X42422Y-134451D01*
X43513Y-134742D01*
X44824Y-135617D01*
G01X63197Y-128617D02*
Y-146117D01*
G01Y-143493D02*
X62324Y-144951D01*
X61013Y-145825D01*
X59485Y-146117D01*
X57739Y-145534D01*
X56429Y-144076D01*
X55555Y-142326D01*
X55337Y-140284D01*
X55555Y-138242D01*
X56429Y-136492D01*
X57739Y-135034D01*
X59485Y-134451D01*
X61013Y-134742D01*
X62105Y-135326D01*
X63197Y-136492D01*
G01X-77660Y-101117D02*
Y-83617D01*
X-71983Y-98200D01*
X-66306Y-83617D01*
Y-101117D01*
G01X-54483D02*
X-55793Y-100825D01*
X-57103Y-99659D01*
X-57977Y-97617D01*
X-58413Y-95284D01*
X-57977Y-92950D01*
X-57103Y-90909D01*
X-55793Y-89742D01*
X-54483Y-89451D01*
X-53173Y-89742D01*
X-51863Y-90909D01*
X-50990Y-92950D01*
X-50771Y-95284D01*
X-50990Y-97617D01*
X-51863Y-99659D01*
X-53173Y-100825D01*
X-54483Y-101117D01*
G01X-33053Y-83617D02*
Y-101117D01*
G01Y-98493D02*
X-33926Y-99951D01*
X-35237Y-100825D01*
X-36765Y-101117D01*
X-38511Y-100534D01*
X-39821Y-99076D01*
X-40695Y-97326D01*
X-40913Y-95284D01*
X-40695Y-93242D01*
X-39821Y-91492D01*
X-38511Y-90034D01*
X-36765Y-89451D01*
X-35237Y-89742D01*
X-34145Y-90326D01*
X-33053Y-91492D01*
G01X-22758Y-93242D02*
X-15771D01*
X-16426Y-91200D01*
X-17518Y-90034D01*
X-19046Y-89451D01*
X-20575Y-89742D01*
X-21885Y-90617D01*
X-22758Y-92659D01*
X-23195Y-94409D01*
Y-96159D01*
X-22758Y-97909D01*
X-21666Y-99659D01*
X-20356Y-100825D01*
X-18828Y-101117D01*
X-17300Y-100534D01*
X-15771Y-98784D01*
G01X-1983Y-101117D02*
Y-83617D01*
G01X110317Y-146117D02*
Y-128617D01*
X107697Y-132117D01*
G01Y-146117D02*
X112937D01*
G01X123669Y-138826D02*
X125197Y-136784D01*
X126507Y-135617D01*
X128254Y-135034D01*
X129782Y-135617D01*
X130874Y-136784D01*
X131747Y-138534D01*
X131965Y-140575D01*
X131747Y-142326D01*
X130874Y-144076D01*
X129563Y-145534D01*
X128035Y-146117D01*
X126289Y-145534D01*
X124760Y-143784D01*
X123887Y-141159D01*
X123669Y-138242D01*
X124105Y-134451D01*
X124760Y-132408D01*
X125852Y-130367D01*
X127380Y-128909D01*
X128909Y-128617D01*
X130437Y-129200D01*
X131529Y-130659D01*
G01X140514Y-142617D02*
X141823Y-144659D01*
X143570Y-145825D01*
X145535Y-146117D01*
X147282Y-145825D01*
X149029Y-144367D01*
X150120Y-142617D01*
X150339Y-140867D01*
X149902Y-138826D01*
X148374Y-137367D01*
X146845Y-136784D01*
X144880D01*
G01X146845D02*
X148155Y-135909D01*
X149247Y-134451D01*
X149684Y-132701D01*
X149247Y-130950D01*
X148155Y-129492D01*
X146190Y-128617D01*
X144225Y-128909D01*
X142260Y-130076D01*
G01X158669Y-138826D02*
X160197Y-136784D01*
X161507Y-135617D01*
X163254Y-135034D01*
X164782Y-135617D01*
X165874Y-136784D01*
X166747Y-138534D01*
X166965Y-140575D01*
X166747Y-142326D01*
X165874Y-144076D01*
X164563Y-145534D01*
X163035Y-146117D01*
X161289Y-145534D01*
X159760Y-143784D01*
X158887Y-141159D01*
X158669Y-138242D01*
X159105Y-134451D01*
X159760Y-132408D01*
X160852Y-130367D01*
X162380Y-128909D01*
X163909Y-128617D01*
X165437Y-129200D01*
X166529Y-130659D01*
G01X180317Y-146117D02*
X181845Y-145825D01*
X183592Y-144951D01*
X184684Y-143493D01*
X185120Y-141450D01*
X184684Y-139409D01*
X183374Y-137659D01*
X181409Y-136784D01*
X179225D01*
X177915Y-136200D01*
X176823Y-134742D01*
X176387Y-132701D01*
X177042Y-130659D01*
X178570Y-129200D01*
X180317Y-128617D01*
X182063Y-129200D01*
X183592Y-130659D01*
X184247Y-132701D01*
X183810Y-134742D01*
X182719Y-136200D01*
X181409Y-136784D01*
X179225D01*
X177260Y-137659D01*
X175950Y-139409D01*
X175514Y-141450D01*
X175950Y-143493D01*
X177042Y-144951D01*
X178789Y-145825D01*
X180317Y-146117D01*
G01X97200Y-101117D02*
Y-83617D01*
X102440D01*
X104187Y-84492D01*
X105497Y-86534D01*
X105934Y-88867D01*
X105497Y-91200D01*
X104405Y-92950D01*
X102440Y-93826D01*
X97200D01*
G01X123870Y-85076D02*
X122560Y-84200D01*
X121032Y-83617D01*
X119285D01*
X117320Y-84492D01*
X115792Y-85950D01*
X114700Y-87701D01*
X113827Y-90617D01*
X113608Y-93242D01*
X114045Y-95867D01*
X114700Y-97617D01*
X116010Y-99367D01*
X117539Y-100534D01*
X119067Y-101117D01*
X120595D01*
X122124Y-100534D01*
X123434Y-99659D01*
X124526Y-98493D01*
G01X138313Y-91784D02*
X139187Y-90909D01*
X139842Y-89451D01*
X140279Y-87408D01*
X139842Y-85659D01*
X138969Y-84492D01*
X137440Y-83617D01*
X131545D01*
Y-101117D01*
X138750D01*
X140279Y-99951D01*
X141152Y-98200D01*
X141589Y-96159D01*
X141152Y-94117D01*
X139842Y-92367D01*
X138313Y-91784D01*
X131545D01*
G01X147517Y-106950D02*
X160617D01*
G01X166545Y-101117D02*
Y-83617D01*
X176589Y-101117D01*
Y-83617D01*
G01X189067Y-101117D02*
X187320Y-100825D01*
X185792Y-99659D01*
X184482Y-97909D01*
X183608Y-95867D01*
X183172Y-93534D01*
Y-91200D01*
X183608Y-88867D01*
X184482Y-86825D01*
X185792Y-85076D01*
X187320Y-83909D01*
X189067Y-83617D01*
X190813Y-83909D01*
X192342Y-85076D01*
X193652Y-86825D01*
X194526Y-88867D01*
X194962Y-91200D01*
Y-93534D01*
X194526Y-95867D01*
X193652Y-97909D01*
X192342Y-99659D01*
X190813Y-100825D01*
X189067Y-101117D01*
G01X258282Y-143784D02*
X260029Y-145242D01*
X261994Y-146117D01*
X263740D01*
X265487Y-145242D01*
X266797Y-143784D01*
X267452Y-141742D01*
X267015Y-139701D01*
X265924Y-137950D01*
X263959Y-136784D01*
X261339Y-136200D01*
X259810Y-135034D01*
X259155Y-132992D01*
X259592Y-130950D01*
X260684Y-129492D01*
X262212Y-128617D01*
X263740D01*
X265269Y-129200D01*
X266579Y-130659D01*
G01X282113Y-136784D02*
X282987Y-135909D01*
X283642Y-134451D01*
X284079Y-132408D01*
X283642Y-130659D01*
X282769Y-129492D01*
X281240Y-128617D01*
X275345D01*
Y-146117D01*
X282550D01*
X284079Y-144951D01*
X284952Y-143200D01*
X285389Y-141159D01*
X284952Y-139117D01*
X283642Y-137367D01*
X282113Y-136784D01*
X275345D01*
G01X239908Y-83617D02*
X245367Y-101117D01*
X250826Y-83617D01*
G01X267234Y-101117D02*
X258500D01*
Y-83617D01*
X267234D01*
G01X263740Y-92075D02*
X258500D01*
G01X276000Y-101117D02*
Y-83617D01*
X281459D01*
X283205Y-84492D01*
X284297Y-85659D01*
X284734Y-87992D01*
X284297Y-90326D01*
X282987Y-91784D01*
X281459Y-92659D01*
X276000D01*
G01X281459D02*
X284734Y-101117D01*
G01X297867Y-101700D02*
X297430Y-101409D01*
Y-100825D01*
X297867Y-100534D01*
X298304Y-100825D01*
Y-101409D01*
X297867Y-101700D01*
G01X377817Y-128617D02*
Y-146117D01*
G01X372795Y-128617D02*
X382839D01*
G01X390732Y-143784D02*
X392479Y-145242D01*
X394444Y-146117D01*
X396190D01*
X397937Y-145242D01*
X399247Y-143784D01*
X399902Y-141742D01*
X399465Y-139701D01*
X398374Y-137950D01*
X396409Y-136784D01*
X393789Y-136200D01*
X392260Y-135034D01*
X391605Y-132992D01*
X392042Y-130950D01*
X393134Y-129492D01*
X394662Y-128617D01*
X396190D01*
X397719Y-129200D01*
X399029Y-130659D01*
G01X410197Y-128617D02*
X415437D01*
G01X412817D02*
Y-146117D01*
G01X410197D02*
X415437D01*
G01X425950Y-128617D02*
Y-146117D01*
X434684D01*
G01X443014D02*
Y-128617D01*
G01X451310D02*
X443014Y-139409D01*
G01X452620Y-146117D02*
X446725Y-134451D01*
G01X373450Y-83617D02*
Y-101117D01*
X382184D01*
G01X399247D02*
Y-89451D01*
G01Y-91492D02*
X398374Y-90326D01*
X397063Y-89742D01*
X395535Y-89451D01*
X394007Y-90034D01*
X392697Y-91200D01*
X391823Y-92950D01*
X391387Y-95284D01*
X391823Y-97617D01*
X392697Y-99367D01*
X394007Y-100534D01*
X395535Y-101117D01*
X397063Y-100825D01*
X398374Y-99951D01*
X399247Y-98784D01*
G01X408232Y-106367D02*
X409542Y-106950D01*
X411289Y-106367D01*
X412380Y-105201D01*
X413254Y-103742D01*
X414563Y-99076D01*
X417402Y-89451D01*
G01X410415D02*
X414563Y-99076D01*
G01X427042Y-93242D02*
X434029D01*
X433374Y-91200D01*
X432282Y-90034D01*
X430754Y-89451D01*
X429225Y-89742D01*
X427915Y-90617D01*
X427042Y-92659D01*
X426605Y-94409D01*
Y-96159D01*
X427042Y-97909D01*
X428134Y-99659D01*
X429444Y-100825D01*
X430972Y-101117D01*
X432500Y-100534D01*
X434029Y-98784D01*
G01X444760Y-101117D02*
Y-89451D01*
G01Y-91784D02*
X445852Y-90617D01*
X446944Y-89742D01*
X448472Y-89451D01*
X449563Y-89742D01*
X450874Y-90617D01*
G01X515564Y-101117D02*
Y-83617D01*
X519930D01*
X521677Y-84492D01*
X522987Y-85659D01*
X524079Y-87408D01*
X524952Y-89451D01*
X525170Y-92367D01*
X524952Y-95284D01*
X524079Y-97326D01*
X522987Y-99076D01*
X521677Y-100242D01*
X519930Y-101117D01*
X515564D01*
G01X534592Y-93242D02*
X541579D01*
X540924Y-91200D01*
X539832Y-90034D01*
X538304Y-89451D01*
X536775Y-89742D01*
X535465Y-90617D01*
X534592Y-92659D01*
X534155Y-94409D01*
Y-96159D01*
X534592Y-97909D01*
X535684Y-99659D01*
X536994Y-100825D01*
X538522Y-101117D01*
X540050Y-100534D01*
X541579Y-98784D01*
G01X552092Y-99076D02*
X553184Y-100242D01*
X554712Y-101117D01*
X556022D01*
X557332Y-100534D01*
X558205Y-99659D01*
X558642Y-98493D01*
X558424Y-96742D01*
X557550Y-95867D01*
X553620Y-94117D01*
X552747Y-92075D01*
X553184Y-90617D01*
X554057Y-89742D01*
X555367Y-89451D01*
X556677Y-89742D01*
X557987Y-90617D01*
G01X572867Y-89451D02*
Y-101117D01*
G01Y-84784D02*
X572430Y-84492D01*
Y-83909D01*
X572867Y-83617D01*
X573304Y-83909D01*
Y-84492D01*
X572867Y-84784D01*
G01X587310Y-105492D02*
X588839Y-106659D01*
X590585Y-106950D01*
X592113Y-106659D01*
X593424Y-105201D01*
X594297Y-103159D01*
Y-89451D01*
G01Y-91784D02*
X593424Y-90617D01*
X592113Y-89742D01*
X590585Y-89451D01*
X588839Y-90034D01*
X587747Y-91200D01*
X586873Y-93242D01*
X586437Y-95284D01*
X586655Y-97034D01*
X587529Y-99076D01*
X588839Y-100534D01*
X590585Y-101117D01*
X591895Y-100825D01*
X593424Y-99659D01*
X594297Y-98493D01*
G01X604155Y-101117D02*
Y-89451D01*
G01Y-92367D02*
X605029Y-90909D01*
X606339Y-89742D01*
X608085Y-89451D01*
X609613Y-89742D01*
X610924Y-90909D01*
X611579Y-92950D01*
Y-101117D01*
G01X622092Y-93242D02*
X629079D01*
X628424Y-91200D01*
X627332Y-90034D01*
X625804Y-89451D01*
X624275Y-89742D01*
X622965Y-90617D01*
X622092Y-92659D01*
X621655Y-94409D01*
Y-96159D01*
X622092Y-97909D01*
X623184Y-99659D01*
X624494Y-100825D01*
X626022Y-101117D01*
X627550Y-100534D01*
X629079Y-98784D01*
G01X639810Y-101117D02*
Y-89451D01*
G01Y-91784D02*
X640902Y-90617D01*
X641994Y-89742D01*
X643522Y-89451D01*
X644613Y-89742D01*
X645924Y-90617D01*
G01X559969Y-128617D02*
X568265D01*
X559969Y-146117D01*
X568265D01*
G01X581617D02*
X579870Y-145825D01*
X578342Y-144659D01*
X577032Y-142909D01*
X576158Y-140867D01*
X575722Y-138534D01*
Y-136200D01*
X576158Y-133867D01*
X577032Y-131825D01*
X578342Y-130076D01*
X579870Y-128909D01*
X581617Y-128617D01*
X583363Y-128909D01*
X584892Y-130076D01*
X586202Y-131825D01*
X587076Y-133867D01*
X587512Y-136200D01*
Y-138534D01*
X587076Y-140867D01*
X586202Y-142909D01*
X584892Y-144659D01*
X583363Y-145825D01*
X581617Y-146117D01*
G01X603484D02*
X594750D01*
Y-128617D01*
X603484D01*
G01X599990Y-137075D02*
X594750D01*
G01X686567Y-128617D02*
X684820Y-129200D01*
X683510Y-130659D01*
X682637Y-132408D01*
X681982Y-134742D01*
X681764Y-137367D01*
X681982Y-139992D01*
X682637Y-142326D01*
X683510Y-144076D01*
X684820Y-145534D01*
X686567Y-146117D01*
X688313Y-145534D01*
X689624Y-144076D01*
X690497Y-142326D01*
X691152Y-139992D01*
X691370Y-137367D01*
X691152Y-134742D01*
X690497Y-132408D01*
X689624Y-130659D01*
X688313Y-129200D01*
X686567Y-128617D01*
G01X699919Y-131534D02*
X701229Y-129784D01*
X702757Y-128909D01*
X704504Y-128617D01*
X706687Y-129200D01*
X708215Y-130659D01*
X708652Y-132408D01*
X708434Y-134159D01*
X707560Y-135617D01*
X703194Y-138534D01*
X701229Y-140575D01*
X699919Y-143493D01*
X699482Y-146117D01*
X708652D01*
G01X717637Y-146700D02*
X725497Y-128617D01*
G01X739067D02*
X737320Y-129200D01*
X736010Y-130659D01*
X735137Y-132408D01*
X734482Y-134742D01*
X734264Y-137367D01*
X734482Y-139992D01*
X735137Y-142326D01*
X736010Y-144076D01*
X737320Y-145534D01*
X739067Y-146117D01*
X740813Y-145534D01*
X742124Y-144076D01*
X742997Y-142326D01*
X743652Y-139992D01*
X743870Y-137367D01*
X743652Y-134742D01*
X742997Y-132408D01*
X742124Y-130659D01*
X740813Y-129200D01*
X739067Y-128617D01*
G01X756130Y-146117D02*
X756567Y-142326D01*
X757222Y-139117D01*
X758095Y-136200D01*
X759187Y-132992D01*
X760934Y-128617D01*
X752200D01*
G01X770137Y-146700D02*
X777997Y-128617D01*
G01X787419Y-131534D02*
X788729Y-129784D01*
X790257Y-128909D01*
X792004Y-128617D01*
X794187Y-129200D01*
X795715Y-130659D01*
X796152Y-132408D01*
X795934Y-134159D01*
X795060Y-135617D01*
X790694Y-138534D01*
X788729Y-140575D01*
X787419Y-143493D01*
X786982Y-146117D01*
X796152D01*
G01X809067Y-128617D02*
X807320Y-129200D01*
X806010Y-130659D01*
X805137Y-132408D01*
X804482Y-134742D01*
X804264Y-137367D01*
X804482Y-139992D01*
X805137Y-142326D01*
X806010Y-144076D01*
X807320Y-145534D01*
X809067Y-146117D01*
X810813Y-145534D01*
X812124Y-144076D01*
X812997Y-142326D01*
X813652Y-139992D01*
X813870Y-137367D01*
X813652Y-134742D01*
X812997Y-132408D01*
X812124Y-130659D01*
X810813Y-129200D01*
X809067Y-128617D01*
G01X826567Y-146117D02*
Y-128617D01*
X823947Y-132117D01*
G01Y-146117D02*
X829187D01*
G01X843630D02*
X844067Y-142326D01*
X844722Y-139117D01*
X845595Y-136200D01*
X846687Y-132992D01*
X848434Y-128617D01*
X839700D01*
G01X734264Y-101117D02*
Y-83617D01*
X738630D01*
X740377Y-84492D01*
X741687Y-85659D01*
X742779Y-87408D01*
X743652Y-89451D01*
X743870Y-92367D01*
X743652Y-95284D01*
X742779Y-97326D01*
X741687Y-99076D01*
X740377Y-100242D01*
X738630Y-101117D01*
X734264D01*
G01X760497D02*
Y-89451D01*
G01Y-91492D02*
X759624Y-90326D01*
X758313Y-89742D01*
X756785Y-89451D01*
X755257Y-90034D01*
X753947Y-91200D01*
X753073Y-92950D01*
X752637Y-95284D01*
X753073Y-97617D01*
X753947Y-99367D01*
X755257Y-100534D01*
X756785Y-101117D01*
X758313Y-100825D01*
X759624Y-99951D01*
X760497Y-98784D01*
G01X774067Y-83617D02*
Y-101117D01*
G01X771010Y-89451D02*
X777124D01*
G01X788292Y-93242D02*
X795279D01*
X794624Y-91200D01*
X793532Y-90034D01*
X792004Y-89451D01*
X790475Y-89742D01*
X789165Y-90617D01*
X788292Y-92659D01*
X787855Y-94409D01*
Y-96159D01*
X788292Y-97909D01*
X789384Y-99659D01*
X790694Y-100825D01*
X792222Y-101117D01*
X793750Y-100534D01*
X795279Y-98784D01*
G01X17333Y45433D02*
X19125D01*
X19500Y45600D01*
X19750Y45933D01*
X19833Y46350D01*
X19750Y46767D01*
X19500Y47100D01*
X19125Y47267D01*
X17333D01*
G01X19500Y48575D02*
X19708Y48908D01*
X19833Y49283D01*
Y49617D01*
X19708Y49950D01*
X19500Y50200D01*
X19208Y50325D01*
X18916Y50242D01*
X18666Y50033D01*
X18500Y49658D01*
X18416Y49158D01*
X18250Y48867D01*
X17958Y48742D01*
X17666Y48825D01*
X17458Y49033D01*
X17333Y49325D01*
Y49617D01*
X17416Y49908D01*
X17625Y50158D01*
G01X18500Y52883D02*
X18375Y53050D01*
X18166Y53175D01*
X17875Y53258D01*
X17625Y53175D01*
X17458Y53008D01*
X17333Y52717D01*
Y51592D01*
X19833D01*
Y52967D01*
X19666Y53258D01*
X19416Y53425D01*
X19125Y53508D01*
X18833Y53425D01*
X18583Y53175D01*
X18500Y52883D01*
Y51592D01*
G01X19833Y55650D02*
X17333D01*
X17833Y55150D01*
G01X19833D02*
Y56150D01*
G01X21904Y35399D02*
Y58499D01*
X61404D01*
Y35399D01*
X21904D01*
G01X1075Y40500D02*
Y43000D01*
G01X2825D02*
Y40500D01*
G01Y41750D02*
X1075D01*
G01X5050Y40500D02*
Y43000D01*
X4550Y42500D01*
G01Y40500D02*
X5550D01*
G01X51000Y24067D02*
X48500D01*
Y25108D01*
X48625Y25442D01*
X48792Y25650D01*
X49125Y25733D01*
X49458Y25650D01*
X49667Y25400D01*
X49792Y25108D01*
Y24067D01*
G01Y25108D02*
X51000Y25733D01*
G01Y28000D02*
X48500D01*
X49000Y27500D01*
G01X51000D02*
Y28500D01*
G01X49958Y30308D02*
X49667Y30600D01*
X49500Y30850D01*
X49417Y31183D01*
X49500Y31475D01*
X49667Y31683D01*
X49917Y31850D01*
X50208Y31892D01*
X50458Y31850D01*
X50708Y31683D01*
X50917Y31433D01*
X51000Y31142D01*
X50917Y30808D01*
X50667Y30517D01*
X50292Y30350D01*
X49875Y30308D01*
X49333Y30392D01*
X49042Y30517D01*
X48750Y30725D01*
X48542Y31017D01*
X48500Y31308D01*
X48583Y31600D01*
X48792Y31808D01*
G01X56800Y27000D02*
Y23000D01*
X64200D01*
G01X85500Y35200D02*
X81500D01*
Y27800D01*
G01X106700Y23500D02*
Y27500D01*
X99300D01*
G01X44000Y24067D02*
X41500D01*
Y25108D01*
X41625Y25442D01*
X41792Y25650D01*
X42125Y25733D01*
X42458Y25650D01*
X42667Y25400D01*
X42792Y25108D01*
Y24067D01*
G01Y25108D02*
X44000Y25733D01*
G01Y28000D02*
X41500D01*
X42000Y27500D01*
G01X44000D02*
Y28500D01*
G01Y31100D02*
X41500D01*
X42000Y30600D01*
G01X44000D02*
Y31600D01*
G01X51700Y19000D02*
Y23000D01*
X44300D01*
G01X100117Y32000D02*
Y34500D01*
X101158D01*
X101492Y34375D01*
X101700Y34208D01*
X101783Y33875D01*
X101700Y33542D01*
X101450Y33333D01*
X101158Y33208D01*
X100117D01*
G01X101158D02*
X101783Y32000D01*
G01X103133Y32500D02*
X103383Y32208D01*
X103717Y32042D01*
X104092Y32000D01*
X104425Y32042D01*
X104758Y32250D01*
X104967Y32500D01*
X105008Y32750D01*
X104925Y33042D01*
X104633Y33250D01*
X104342Y33333D01*
X103967D01*
G01X104342D02*
X104592Y33458D01*
X104800Y33667D01*
X104883Y33917D01*
X104800Y34167D01*
X104592Y34375D01*
X104217Y34500D01*
X103842Y34458D01*
X103467Y34292D01*
G01X99800Y23000D02*
Y19000D01*
X107200D01*
G01X80117Y24000D02*
Y26500D01*
X81158D01*
X81492Y26375D01*
X81700Y26208D01*
X81783Y25875D01*
X81700Y25542D01*
X81450Y25333D01*
X81158Y25208D01*
X80117D01*
G01X81158D02*
X81783Y24000D01*
G01X83133Y24375D02*
X83383Y24167D01*
X83675Y24042D01*
X84050Y24000D01*
X84425Y24083D01*
X84717Y24250D01*
X84925Y24542D01*
X84967Y24875D01*
X84883Y25208D01*
X84675Y25417D01*
X84383Y25583D01*
X84092Y25625D01*
X83800Y25583D01*
X83425Y25417D01*
X83550Y26500D01*
X84675D01*
G01X94200Y19000D02*
Y23000D01*
X86800D01*
G01X69617Y20000D02*
Y22500D01*
X70658D01*
X70992Y22375D01*
X71200Y22208D01*
X71283Y21875D01*
X71200Y21542D01*
X70950Y21333D01*
X70658Y21208D01*
X69617D01*
G01X70658D02*
X71283Y20000D01*
G01X73467D02*
X73550Y20542D01*
X73675Y21000D01*
X73842Y21417D01*
X74050Y21875D01*
X74383Y22500D01*
X72717D01*
G01X82700Y19000D02*
Y23000D01*
X75300D01*
G01X55500Y21117D02*
X53000D01*
Y22158D01*
X53125Y22492D01*
X53292Y22700D01*
X53625Y22783D01*
X53958Y22700D01*
X54167Y22450D01*
X54292Y22158D01*
Y21117D01*
G01Y22158D02*
X55500Y22783D01*
G01X55208Y24342D02*
X55417Y24633D01*
X55500Y24967D01*
X55417Y25300D01*
X55167Y25592D01*
X54792Y25800D01*
X54417Y25883D01*
X53958D01*
X53583Y25800D01*
X53250Y25592D01*
X53083Y25342D01*
X53000Y25050D01*
X53083Y24717D01*
X53250Y24467D01*
X53500Y24300D01*
X53833Y24217D01*
X54125Y24300D01*
X54417Y24508D01*
X54583Y24758D01*
X54625Y25050D01*
X54542Y25383D01*
X54333Y25633D01*
X53958Y25883D01*
G01X57300Y23000D02*
Y19000D01*
X64700D01*
G01X99300Y31500D02*
Y27500D01*
X106700D01*
G01X53617Y31500D02*
Y34000D01*
X54658D01*
X54992Y33875D01*
X55200Y33708D01*
X55283Y33375D01*
X55200Y33042D01*
X54950Y32833D01*
X54658Y32708D01*
X53617D01*
G01X54658D02*
X55283Y31500D01*
G01X57550D02*
X57842Y31542D01*
X58175Y31667D01*
X58383Y31875D01*
X58467Y32167D01*
X58383Y32458D01*
X58133Y32708D01*
X57758Y32833D01*
X57342D01*
X57092Y32917D01*
X56883Y33125D01*
X56800Y33417D01*
X56925Y33708D01*
X57217Y33917D01*
X57550Y34000D01*
X57883Y33917D01*
X58175Y33708D01*
X58300Y33417D01*
X58217Y33125D01*
X58008Y32917D01*
X57758Y32833D01*
X57342D01*
X56967Y32708D01*
X56717Y32458D01*
X56633Y32167D01*
X56717Y31875D01*
X56925Y31667D01*
X57258Y31542D01*
X57550Y31500D01*
G01X52300Y31000D02*
Y27000D01*
X59700D01*
G01X113460Y993D02*
Y18693D01*
X122760D01*
Y993D01*
X113460D01*
G01X109500Y8017D02*
X112000D01*
Y9683D01*
G01Y12783D02*
Y11117D01*
X109500D01*
Y12783D01*
G01X110708Y12117D02*
Y11117D01*
G01X112000Y14133D02*
X109500D01*
Y14967D01*
X109625Y15300D01*
X109792Y15550D01*
X110042Y15758D01*
X110333Y15925D01*
X110750Y15967D01*
X111167Y15925D01*
X111458Y15758D01*
X111708Y15550D01*
X111875Y15300D01*
X112000Y14967D01*
Y14133D01*
G01X109917Y17358D02*
X109667Y17608D01*
X109542Y17900D01*
X109500Y18233D01*
X109583Y18650D01*
X109792Y18942D01*
X110042Y19025D01*
X110292Y18983D01*
X110500Y18817D01*
X110917Y17983D01*
X111208Y17608D01*
X111625Y17358D01*
X112000Y17275D01*
Y19025D01*
G01X99287Y993D02*
Y18693D01*
X108587D01*
Y993D01*
X99287D01*
G01X95500Y8017D02*
X98000D01*
Y9683D01*
G01Y12783D02*
Y11117D01*
X95500D01*
Y12783D01*
G01X96708Y12117D02*
Y11117D01*
G01X98000Y14133D02*
X95500D01*
Y14967D01*
X95625Y15300D01*
X95792Y15550D01*
X96042Y15758D01*
X96333Y15925D01*
X96750Y15967D01*
X97167Y15925D01*
X97458Y15758D01*
X97708Y15550D01*
X97875Y15300D01*
X98000Y14967D01*
Y14133D01*
G01X97500Y17233D02*
X97792Y17483D01*
X97958Y17817D01*
X98000Y18192D01*
X97958Y18525D01*
X97750Y18858D01*
X97500Y19067D01*
X97250Y19108D01*
X96958Y19025D01*
X96750Y18733D01*
X96667Y18442D01*
Y18067D01*
G01Y18442D02*
X96542Y18692D01*
X96333Y18900D01*
X96083Y18983D01*
X95833Y18900D01*
X95625Y18692D01*
X95500Y18317D01*
X95542Y17942D01*
X95708Y17567D01*
G01X85114Y993D02*
Y18693D01*
X94414D01*
Y993D01*
X85114D01*
G01X81500Y7517D02*
X84000D01*
Y9183D01*
G01Y12283D02*
Y10617D01*
X81500D01*
Y12283D01*
G01X82708Y11617D02*
Y10617D01*
G01X84000Y13633D02*
X81500D01*
Y14467D01*
X81625Y14800D01*
X81792Y15050D01*
X82042Y15258D01*
X82333Y15425D01*
X82750Y15467D01*
X83167Y15425D01*
X83458Y15258D01*
X83708Y15050D01*
X83875Y14800D01*
X84000Y14467D01*
Y13633D01*
G01Y18150D02*
X81500D01*
X83292Y16608D01*
Y18692D01*
G01X70941Y993D02*
Y18693D01*
X80241D01*
Y993D01*
X70941D01*
G01X67000Y8017D02*
X69500D01*
Y9683D01*
G01Y12783D02*
Y11117D01*
X67000D01*
Y12783D01*
G01X68208Y12117D02*
Y11117D01*
G01X69500Y14133D02*
X67000D01*
Y14967D01*
X67125Y15300D01*
X67292Y15550D01*
X67542Y15758D01*
X67833Y15925D01*
X68250Y15967D01*
X68667Y15925D01*
X68958Y15758D01*
X69208Y15550D01*
X69375Y15300D01*
X69500Y14967D01*
Y14133D01*
G01X69125Y17233D02*
X69333Y17483D01*
X69458Y17775D01*
X69500Y18150D01*
X69417Y18525D01*
X69250Y18817D01*
X68958Y19025D01*
X68625Y19067D01*
X68292Y18983D01*
X68083Y18775D01*
X67917Y18483D01*
X67875Y18192D01*
X67917Y17900D01*
X68083Y17525D01*
X67000Y17650D01*
Y18775D01*
G01X56767Y993D02*
Y18693D01*
X66067D01*
Y993D01*
X56767D01*
G01X53000Y8017D02*
X55500D01*
Y9683D01*
G01Y12783D02*
Y11117D01*
X53000D01*
Y12783D01*
G01X54208Y12117D02*
Y11117D01*
G01X55500Y14133D02*
X53000D01*
Y14967D01*
X53125Y15300D01*
X53292Y15550D01*
X53542Y15758D01*
X53833Y15925D01*
X54250Y15967D01*
X54667Y15925D01*
X54958Y15758D01*
X55208Y15550D01*
X55375Y15300D01*
X55500Y14967D01*
Y14133D01*
G01X54458Y17358D02*
X54167Y17650D01*
X54000Y17900D01*
X53917Y18233D01*
X54000Y18525D01*
X54167Y18733D01*
X54417Y18900D01*
X54708Y18942D01*
X54958Y18900D01*
X55208Y18733D01*
X55417Y18483D01*
X55500Y18192D01*
X55417Y17858D01*
X55167Y17567D01*
X54792Y17400D01*
X54375Y17358D01*
X53833Y17442D01*
X53542Y17567D01*
X53250Y17775D01*
X53042Y18067D01*
X53000Y18358D01*
X53083Y18650D01*
X53292Y18858D01*
G01X42594Y993D02*
Y18693D01*
X51894D01*
Y993D01*
X42594D01*
G01X78700Y24500D02*
X65300D01*
G01X78700Y34500D02*
Y24500D01*
G01X65300D02*
Y34500D01*
G01X86500Y24800D02*
Y38200D01*
G01X96500Y24800D02*
X86500D01*
G01X96500Y38200D02*
Y24800D01*
G01X108500Y20300D02*
Y33700D01*
G01X118500Y20300D02*
X108500D01*
G01X74417Y60500D02*
Y58000D01*
X76083D01*
G01X78683Y59333D02*
X78850Y59458D01*
X78975Y59667D01*
X79058Y59958D01*
X78975Y60208D01*
X78808Y60375D01*
X78517Y60500D01*
X77392D01*
Y58000D01*
X78767D01*
X79058Y58167D01*
X79225Y58417D01*
X79308Y58708D01*
X79225Y59000D01*
X78975Y59250D01*
X78683Y59333D01*
X77392D01*
G01X82367Y60292D02*
X82117Y60417D01*
X81825Y60500D01*
X81492D01*
X81117Y60375D01*
X80825Y60167D01*
X80617Y59917D01*
X80450Y59500D01*
X80408Y59125D01*
X80492Y58750D01*
X80617Y58500D01*
X80867Y58250D01*
X81158Y58083D01*
X81450Y58000D01*
X81742D01*
X82033Y58083D01*
X82283Y58208D01*
X82492Y58375D01*
G01X86817Y60500D02*
Y58000D01*
X88483D01*
G01X91583D02*
X89917D01*
Y60500D01*
X91583D01*
G01X90917Y59292D02*
X89917D01*
G01X92933Y58000D02*
Y60500D01*
X93767D01*
X94100Y60375D01*
X94350Y60208D01*
X94558Y59958D01*
X94725Y59667D01*
X94767Y59250D01*
X94725Y58833D01*
X94558Y58542D01*
X94350Y58292D01*
X94100Y58125D01*
X93767Y58000D01*
X92933D01*
G01X100717Y59458D02*
X100425Y59625D01*
X100175Y59667D01*
X99842Y59583D01*
X99592Y59417D01*
X99425Y59125D01*
X99383Y58833D01*
X99425Y58542D01*
X99592Y58292D01*
X99842Y58083D01*
X100175Y58000D01*
X100467Y58083D01*
X100717Y58250D01*
G01X103900Y58000D02*
Y59667D01*
G01Y59375D02*
X103733Y59542D01*
X103483Y59625D01*
X103192Y59667D01*
X102900Y59583D01*
X102650Y59417D01*
X102483Y59167D01*
X102400Y58833D01*
X102483Y58500D01*
X102650Y58250D01*
X102900Y58083D01*
X103192Y58000D01*
X103483Y58042D01*
X103733Y58167D01*
X103900Y58333D01*
G01X105667Y58000D02*
Y59667D01*
G01Y59333D02*
X105875Y59500D01*
X106083Y59625D01*
X106375Y59667D01*
X106583Y59625D01*
X106833Y59500D01*
G01X110100Y60500D02*
Y58000D01*
G01Y58375D02*
X109933Y58167D01*
X109683Y58042D01*
X109392Y58000D01*
X109058Y58083D01*
X108808Y58292D01*
X108642Y58542D01*
X108600Y58833D01*
X108642Y59125D01*
X108808Y59375D01*
X109058Y59583D01*
X109392Y59667D01*
X109683Y59625D01*
X109892Y59542D01*
X110100Y59375D01*
G01X115750Y58000D02*
Y60500D01*
X115250Y60000D01*
G01Y58000D02*
X116250D01*
G01X118058Y59042D02*
X118350Y59333D01*
X118600Y59500D01*
X118933Y59583D01*
X119225Y59500D01*
X119433Y59333D01*
X119600Y59083D01*
X119642Y58792D01*
X119600Y58542D01*
X119433Y58292D01*
X119183Y58083D01*
X118892Y58000D01*
X118558Y58083D01*
X118267Y58333D01*
X118100Y58708D01*
X118058Y59125D01*
X118142Y59667D01*
X118267Y59958D01*
X118475Y60250D01*
X118767Y60458D01*
X119058Y60500D01*
X119350Y60417D01*
X119558Y60208D01*
G01X121033Y58500D02*
X121283Y58208D01*
X121617Y58042D01*
X121992Y58000D01*
X122325Y58042D01*
X122658Y58250D01*
X122867Y58500D01*
X122908Y58750D01*
X122825Y59042D01*
X122533Y59250D01*
X122242Y59333D01*
X121867D01*
G01X122242D02*
X122492Y59458D01*
X122700Y59667D01*
X122783Y59917D01*
X122700Y60167D01*
X122492Y60375D01*
X122117Y60500D01*
X121742Y60458D01*
X121367Y60292D01*
G01X124258Y59042D02*
X124550Y59333D01*
X124800Y59500D01*
X125133Y59583D01*
X125425Y59500D01*
X125633Y59333D01*
X125800Y59083D01*
X125842Y58792D01*
X125800Y58542D01*
X125633Y58292D01*
X125383Y58083D01*
X125092Y58000D01*
X124758Y58083D01*
X124467Y58333D01*
X124300Y58708D01*
X124258Y59125D01*
X124342Y59667D01*
X124467Y59958D01*
X124675Y60250D01*
X124967Y60458D01*
X125258Y60500D01*
X125550Y60417D01*
X125758Y60208D01*
G01X128150Y58000D02*
X128442Y58042D01*
X128775Y58167D01*
X128983Y58375D01*
X129067Y58667D01*
X128983Y58958D01*
X128733Y59208D01*
X128358Y59333D01*
X127942D01*
X127692Y59417D01*
X127483Y59625D01*
X127400Y59917D01*
X127525Y60208D01*
X127817Y60417D01*
X128150Y60500D01*
X128483Y60417D01*
X128775Y60208D01*
X128900Y59917D01*
X128817Y59625D01*
X128608Y59417D01*
X128358Y59333D01*
X127942D01*
X127567Y59208D01*
X127317Y58958D01*
X127233Y58667D01*
X127317Y58375D01*
X127525Y58167D01*
X127858Y58042D01*
X128150Y58000D01*
G01X130708Y58833D02*
X131792D01*
G01X133475Y58333D02*
X133808Y58125D01*
X134183Y58000D01*
X134517D01*
X134850Y58125D01*
X135100Y58333D01*
X135225Y58625D01*
X135142Y58917D01*
X134933Y59167D01*
X134558Y59333D01*
X134058Y59417D01*
X133767Y59583D01*
X133642Y59875D01*
X133725Y60167D01*
X133933Y60375D01*
X134225Y60500D01*
X134517D01*
X134808Y60417D01*
X135058Y60208D01*
G01X137783Y59333D02*
X137950Y59458D01*
X138075Y59667D01*
X138158Y59958D01*
X138075Y60208D01*
X137908Y60375D01*
X137617Y60500D01*
X136492D01*
Y58000D01*
X137867D01*
X138158Y58167D01*
X138325Y58417D01*
X138408Y58708D01*
X138325Y59000D01*
X138075Y59250D01*
X137783Y59333D01*
X136492D01*
G01X100583Y55333D02*
X100750Y55458D01*
X100875Y55667D01*
X100958Y55958D01*
X100875Y56208D01*
X100708Y56375D01*
X100417Y56500D01*
X99292D01*
Y54000D01*
X100667D01*
X100958Y54167D01*
X101125Y54417D01*
X101208Y54708D01*
X101125Y55000D01*
X100875Y55250D01*
X100583Y55333D01*
X99292D01*
G01X103850Y54000D02*
Y56500D01*
X102308Y54708D01*
X104392D01*
G01X106450Y54000D02*
X106742Y54042D01*
X107075Y54167D01*
X107283Y54375D01*
X107367Y54667D01*
X107283Y54958D01*
X107033Y55208D01*
X106658Y55333D01*
X106242D01*
X105992Y55417D01*
X105783Y55625D01*
X105700Y55917D01*
X105825Y56208D01*
X106117Y56417D01*
X106450Y56500D01*
X106783Y56417D01*
X107075Y56208D01*
X107200Y55917D01*
X107117Y55625D01*
X106908Y55417D01*
X106658Y55333D01*
X106242D01*
X105867Y55208D01*
X105617Y54958D01*
X105533Y54667D01*
X105617Y54375D01*
X105825Y54167D01*
X106158Y54042D01*
X106450Y54000D01*
G01X109550Y53917D02*
X109467Y53958D01*
Y54042D01*
X109550Y54083D01*
X109633Y54042D01*
Y53958D01*
X109550Y53917D01*
G01X112650Y56500D02*
X112317Y56417D01*
X112067Y56208D01*
X111900Y55958D01*
X111775Y55625D01*
X111733Y55250D01*
X111775Y54875D01*
X111900Y54542D01*
X112067Y54292D01*
X112317Y54083D01*
X112650Y54000D01*
X112983Y54083D01*
X113233Y54292D01*
X113400Y54542D01*
X113525Y54875D01*
X113567Y55250D01*
X113525Y55625D01*
X113400Y55958D01*
X113233Y56208D01*
X112983Y56417D01*
X112650Y56500D01*
G01X115750Y54000D02*
Y56500D01*
X115250Y56000D01*
G01Y54000D02*
X116250D01*
G01X118767D02*
X118850Y54542D01*
X118975Y55000D01*
X119142Y55417D01*
X119350Y55875D01*
X119683Y56500D01*
X118017D01*
G01X121950D02*
X121617Y56417D01*
X121367Y56208D01*
X121200Y55958D01*
X121075Y55625D01*
X121033Y55250D01*
X121075Y54875D01*
X121200Y54542D01*
X121367Y54292D01*
X121617Y54083D01*
X121950Y54000D01*
X122283Y54083D01*
X122533Y54292D01*
X122700Y54542D01*
X122825Y54875D01*
X122867Y55250D01*
X122825Y55625D01*
X122700Y55958D01*
X122533Y56208D01*
X122283Y56417D01*
X121950Y56500D01*
G01X125550Y54000D02*
Y56500D01*
X124008Y54708D01*
X126092D01*
G01X128150Y53917D02*
X128067Y53958D01*
Y54042D01*
X128150Y54083D01*
X128233Y54042D01*
Y53958D01*
X128150Y53917D01*
G01X131250Y56500D02*
X130917Y56417D01*
X130667Y56208D01*
X130500Y55958D01*
X130375Y55625D01*
X130333Y55250D01*
X130375Y54875D01*
X130500Y54542D01*
X130667Y54292D01*
X130917Y54083D01*
X131250Y54000D01*
X131583Y54083D01*
X131833Y54292D01*
X132000Y54542D01*
X132125Y54875D01*
X132167Y55250D01*
X132125Y55625D01*
X132000Y55958D01*
X131833Y56208D01*
X131583Y56417D01*
X131250Y56500D01*
G01X134350D02*
X134017Y56417D01*
X133767Y56208D01*
X133600Y55958D01*
X133475Y55625D01*
X133433Y55250D01*
X133475Y54875D01*
X133600Y54542D01*
X133767Y54292D01*
X134017Y54083D01*
X134350Y54000D01*
X134683Y54083D01*
X134933Y54292D01*
X135100Y54542D01*
X135225Y54875D01*
X135267Y55250D01*
X135225Y55625D01*
X135100Y55958D01*
X134933Y56208D01*
X134683Y56417D01*
X134350Y56500D01*
G01X136575Y54333D02*
X136908Y54125D01*
X137283Y54000D01*
X137617D01*
X137950Y54125D01*
X138200Y54333D01*
X138325Y54625D01*
X138242Y54917D01*
X138033Y55167D01*
X137658Y55333D01*
X137158Y55417D01*
X136867Y55583D01*
X136742Y55875D01*
X136825Y56167D01*
X137033Y56375D01*
X137325Y56500D01*
X137617D01*
X137908Y56417D01*
X138158Y56208D01*
G01X140883Y55333D02*
X141050Y55458D01*
X141175Y55667D01*
X141258Y55958D01*
X141175Y56208D01*
X141008Y56375D01*
X140717Y56500D01*
X139592D01*
Y54000D01*
X140967D01*
X141258Y54167D01*
X141425Y54417D01*
X141508Y54708D01*
X141425Y55000D01*
X141175Y55250D01*
X140883Y55333D01*
X139592D01*
G01X94667Y48000D02*
Y50500D01*
X95750Y48417D01*
X96833Y50500D01*
Y48000D01*
G01X97808D02*
X98850Y50500D01*
X99892Y48000D01*
G01X99517Y48875D02*
X98183D01*
G01X101033Y48000D02*
Y50500D01*
X101867D01*
X102200Y50375D01*
X102450Y50208D01*
X102658Y49958D01*
X102825Y49667D01*
X102867Y49250D01*
X102825Y48833D01*
X102658Y48542D01*
X102450Y48292D01*
X102200Y48125D01*
X101867Y48000D01*
X101033D01*
G01X105883D02*
X104217D01*
Y50500D01*
X105883D01*
G01X105217Y49292D02*
X104217D01*
G01X110750Y50500D02*
X111750D01*
G01X111250D02*
Y48000D01*
G01X110750D02*
X111750D01*
G01X113392D02*
Y50500D01*
X115308Y48000D01*
Y50500D01*
G01X120550D02*
Y48000D01*
G01X119592Y50500D02*
X121508D01*
G01X122608Y48000D02*
X123650Y50500D01*
X124692Y48000D01*
G01X124317Y48875D02*
X122983D01*
G01X126250Y50500D02*
X127250D01*
G01X126750D02*
Y48000D01*
G01X126250D02*
X127250D01*
G01X128600Y50500D02*
X129183Y48000D01*
X129850Y50500D01*
X130517Y48000D01*
X131100Y50500D01*
G01X131908Y48000D02*
X132950Y50500D01*
X133992Y48000D01*
G01X133617Y48875D02*
X132283D01*
G01X135092Y48000D02*
Y50500D01*
X137008Y48000D01*
Y50500D01*
G01X68567Y36000D02*
Y38500D01*
X69608D01*
X69942Y38375D01*
X70150Y38208D01*
X70233Y37875D01*
X70150Y37542D01*
X69900Y37333D01*
X69608Y37208D01*
X68567D01*
G01X69608D02*
X70233Y36000D01*
G01X72500D02*
Y38500D01*
X72000Y38000D01*
G01Y36000D02*
X73000D01*
G01X74683Y36375D02*
X74933Y36167D01*
X75225Y36042D01*
X75600Y36000D01*
X75975Y36083D01*
X76267Y36250D01*
X76475Y36542D01*
X76517Y36875D01*
X76433Y37208D01*
X76225Y37417D01*
X75933Y37583D01*
X75642Y37625D01*
X75350Y37583D01*
X74975Y37417D01*
X75100Y38500D01*
X76225D01*
G01X98567Y36000D02*
Y38500D01*
X99608D01*
X99942Y38375D01*
X100150Y38208D01*
X100233Y37875D01*
X100150Y37542D01*
X99900Y37333D01*
X99608Y37208D01*
X98567D01*
G01X99608D02*
X100233Y36000D01*
G01X102500D02*
Y38500D01*
X102000Y38000D01*
G01Y36000D02*
X103000D01*
G01X106100D02*
Y38500D01*
X104558Y36708D01*
X106642D01*
G01X95617Y40000D02*
Y42500D01*
X96658D01*
X96992Y42375D01*
X97200Y42208D01*
X97283Y41875D01*
X97200Y41542D01*
X96950Y41333D01*
X96658Y41208D01*
X95617D01*
G01X96658D02*
X97283Y40000D01*
G01X100050D02*
Y42500D01*
X98508Y40708D01*
X100592D01*
G01X80117Y40000D02*
Y42500D01*
X81158D01*
X81492Y42375D01*
X81700Y42208D01*
X81783Y41875D01*
X81700Y41542D01*
X81450Y41333D01*
X81158Y41208D01*
X80117D01*
G01X81158D02*
X81783Y40000D01*
G01X83258Y41042D02*
X83550Y41333D01*
X83800Y41500D01*
X84133Y41583D01*
X84425Y41500D01*
X84633Y41333D01*
X84800Y41083D01*
X84842Y40792D01*
X84800Y40542D01*
X84633Y40292D01*
X84383Y40083D01*
X84092Y40000D01*
X83758Y40083D01*
X83467Y40333D01*
X83300Y40708D01*
X83258Y41125D01*
X83342Y41667D01*
X83467Y41958D01*
X83675Y42250D01*
X83967Y42458D01*
X84258Y42500D01*
X84550Y42417D01*
X84758Y42208D01*
G01X77800Y39500D02*
Y35500D01*
X85200D01*
G01X66658Y54500D02*
Y57000D01*
X68242D01*
G01X67658Y55792D02*
X66658D01*
G01X70550Y54500D02*
Y57000D01*
X70050Y56500D01*
G01Y54500D02*
X71050D01*
G01X66950Y53050D02*
Y39950D01*
G01X75050Y53050D02*
X66950D01*
G01X75050Y39950D02*
Y53050D01*
G01X66950Y39950D02*
X75050D01*
G01X82033Y54000D02*
Y56500D01*
X82867D01*
X83200Y56375D01*
X83450Y56208D01*
X83658Y55958D01*
X83825Y55667D01*
X83867Y55250D01*
X83825Y54833D01*
X83658Y54542D01*
X83450Y54292D01*
X83200Y54125D01*
X82867Y54000D01*
X82033D01*
G01X86050D02*
Y56500D01*
X85550Y56000D01*
G01Y54000D02*
X86550D01*
G01X76000Y52500D02*
X92100D01*
G01X76000Y45500D02*
Y52500D01*
G01X92100Y45500D02*
X76000D01*
G01X92100Y52500D02*
Y45500D01*
G01X63208Y50367D02*
X63083Y50117D01*
X63000Y49825D01*
Y49492D01*
X63125Y49117D01*
X63333Y48825D01*
X63583Y48617D01*
X64000Y48450D01*
X64375Y48408D01*
X64750Y48492D01*
X65000Y48617D01*
X65250Y48867D01*
X65417Y49158D01*
X65500Y49450D01*
Y49742D01*
X65417Y50033D01*
X65292Y50283D01*
X65125Y50492D01*
G01X65500Y52550D02*
X63000D01*
X63500Y52050D01*
G01X65500D02*
Y53050D01*
G01X62533Y39000D02*
Y37208D01*
X62700Y36833D01*
X63033Y36583D01*
X63450Y36500D01*
X63867Y36583D01*
X64200Y36833D01*
X64367Y37208D01*
Y39000D01*
G01X67050Y36500D02*
Y39000D01*
X65508Y37208D01*
X67592D01*
G01X65300Y34500D02*
X78700D01*
G01X88533Y42500D02*
Y40708D01*
X88700Y40333D01*
X89033Y40083D01*
X89450Y40000D01*
X89867Y40083D01*
X90200Y40333D01*
X90367Y40708D01*
Y42500D01*
G01X91633Y40500D02*
X91883Y40208D01*
X92217Y40042D01*
X92592Y40000D01*
X92925Y40042D01*
X93258Y40250D01*
X93467Y40500D01*
X93508Y40750D01*
X93425Y41042D01*
X93133Y41250D01*
X92842Y41333D01*
X92467D01*
G01X92842D02*
X93092Y41458D01*
X93300Y41667D01*
X93383Y41917D01*
X93300Y42167D01*
X93092Y42375D01*
X92717Y42500D01*
X92342Y42458D01*
X91967Y42292D01*
G01X86500Y38200D02*
X96500D01*
G01X113533Y38500D02*
Y36708D01*
X113700Y36333D01*
X114033Y36083D01*
X114450Y36000D01*
X114867Y36083D01*
X115200Y36333D01*
X115367Y36708D01*
Y38500D01*
G01X116758Y38083D02*
X117008Y38333D01*
X117300Y38458D01*
X117633Y38500D01*
X118050Y38417D01*
X118342Y38208D01*
X118425Y37958D01*
X118383Y37708D01*
X118217Y37500D01*
X117383Y37083D01*
X117008Y36792D01*
X116758Y36375D01*
X116675Y36000D01*
X118425D01*
G01X108500Y33700D02*
X118500D01*
G01X135000Y8067D02*
X132500D01*
Y9108D01*
X132625Y9442D01*
X132792Y9650D01*
X133125Y9733D01*
X133458Y9650D01*
X133667Y9400D01*
X133792Y9108D01*
Y8067D01*
G01Y9108D02*
X135000Y9733D01*
G01Y12000D02*
X132500D01*
X133000Y11500D01*
G01X135000D02*
Y12500D01*
G01X134500Y14183D02*
X134792Y14433D01*
X134958Y14767D01*
X135000Y15142D01*
X134958Y15475D01*
X134750Y15808D01*
X134500Y16017D01*
X134250Y16058D01*
X133958Y15975D01*
X133750Y15683D01*
X133667Y15392D01*
Y15017D01*
G01Y15392D02*
X133542Y15642D01*
X133333Y15850D01*
X133083Y15933D01*
X132833Y15850D01*
X132625Y15642D01*
X132500Y15267D01*
X132542Y14892D01*
X132708Y14517D01*
G01X135500Y24200D02*
X131500D01*
Y16800D01*
G01X125117Y8000D02*
Y10500D01*
X126158D01*
X126492Y10375D01*
X126700Y10208D01*
X126783Y9875D01*
X126700Y9542D01*
X126450Y9333D01*
X126158Y9208D01*
X125117D01*
G01X126158D02*
X126783Y8000D01*
G01X129050D02*
Y10500D01*
X128550Y10000D01*
G01Y8000D02*
X129550D01*
G01X124000Y11800D02*
X128000D01*
Y19200D01*
G01X131500Y24300D02*
X135500D01*
Y31700D01*
G01X125517Y6000D02*
Y3500D01*
X127183D01*
G01X130283D02*
X128617D01*
Y6000D01*
X130283D01*
G01X129617Y4792D02*
X128617D01*
G01X131633Y3500D02*
Y6000D01*
X132467D01*
X132800Y5875D01*
X133050Y5708D01*
X133258Y5458D01*
X133425Y5167D01*
X133467Y4750D01*
X133425Y4333D01*
X133258Y4042D01*
X133050Y3792D01*
X132800Y3625D01*
X132467Y3500D01*
X131633D01*
G01X135650D02*
Y6000D01*
X135150Y5500D01*
G01Y3500D02*
X136150D01*
G01X118500Y33700D02*
Y20300D01*
G01X120500D02*
Y33700D01*
G01X130500Y20300D02*
X120500D01*
G01X130500Y33700D02*
Y20300D01*
G01X144881Y50037D02*
Y57837D01*
X157481D01*
Y50037D01*
X144881D01*
G01X148381Y56437D02*
X147781Y56337D01*
X147281Y55837D01*
X146881Y55337D01*
X146681Y54737D01*
X146581Y53937D01*
X146681Y53237D01*
X146881Y52537D01*
X147281Y52037D01*
X147781Y51637D01*
X148381Y51437D01*
X149081Y51637D01*
X149581Y52037D01*
X149881Y52537D01*
X150181Y53237D01*
X150281Y53937D01*
X150181Y54737D01*
X149881Y55337D01*
X149581Y55837D01*
X149081Y56337D01*
X148381Y56437D01*
G01X153981Y51437D02*
Y56437D01*
X152981Y55437D01*
G01Y51437D02*
X154981D01*
G01X132617Y33000D02*
Y35500D01*
X133658D01*
X133992Y35375D01*
X134200Y35208D01*
X134283Y34875D01*
X134200Y34542D01*
X133950Y34333D01*
X133658Y34208D01*
X132617D01*
G01X133658D02*
X134283Y33000D01*
G01X135758Y35083D02*
X136008Y35333D01*
X136300Y35458D01*
X136633Y35500D01*
X137050Y35417D01*
X137342Y35208D01*
X137425Y34958D01*
X137383Y34708D01*
X137217Y34500D01*
X136383Y34083D01*
X136008Y33792D01*
X135758Y33375D01*
X135675Y33000D01*
X137425D01*
G01X170575Y42000D02*
Y44500D01*
G01X172325D02*
Y42000D01*
G01Y43250D02*
X170575D01*
G01X173758Y44083D02*
X174008Y44333D01*
X174300Y44458D01*
X174633Y44500D01*
X175050Y44417D01*
X175342Y44208D01*
X175425Y43958D01*
X175383Y43708D01*
X175217Y43500D01*
X174383Y43083D01*
X174008Y42792D01*
X173758Y42375D01*
X173675Y42000D01*
X175425D01*
G01X121033Y38500D02*
Y36708D01*
X121200Y36333D01*
X121533Y36083D01*
X121950Y36000D01*
X122367Y36083D01*
X122700Y36333D01*
X122867Y36708D01*
Y38500D01*
G01X125050Y36000D02*
Y38500D01*
X124550Y38000D01*
G01Y36000D02*
X125550D01*
G01X120500Y33700D02*
X130500D01*
G01X144881Y119722D02*
Y127522D01*
X157481D01*
Y119722D01*
X144881D01*
G01X148381Y126122D02*
X147781Y126022D01*
X147281Y125522D01*
X146881Y125022D01*
X146681Y124422D01*
X146581Y123622D01*
X146681Y122922D01*
X146881Y122222D01*
X147281Y121722D01*
X147781Y121322D01*
X148381Y121122D01*
X149081Y121322D01*
X149581Y121722D01*
X149881Y122222D01*
X150181Y122922D01*
X150281Y123622D01*
X150181Y124422D01*
X149881Y125022D01*
X149581Y125522D01*
X149081Y126022D01*
X148381Y126122D01*
G01X154981Y121122D02*
Y126122D01*
X151881Y122522D01*
X156081D01*
G01X144881Y189407D02*
Y197207D01*
X157481D01*
Y189407D01*
X144881D01*
G01X148381Y195807D02*
X147781Y195707D01*
X147281Y195207D01*
X146881Y194707D01*
X146681Y194107D01*
X146581Y193307D01*
X146681Y192607D01*
X146881Y191907D01*
X147281Y191407D01*
X147781Y191007D01*
X148381Y190807D01*
X149081Y191007D01*
X149581Y191407D01*
X149881Y191907D01*
X150181Y192607D01*
X150281Y193307D01*
X150181Y194107D01*
X149881Y194707D01*
X149581Y195207D01*
X149081Y195707D01*
X148381Y195807D01*
G01X153881Y190807D02*
X153981Y191907D01*
X154581Y193707D01*
X154981Y194607D01*
X155681Y195807D01*
X152381D01*
G01X144881Y259092D02*
Y266892D01*
X157481D01*
Y259092D01*
X144881D01*
G01X148381Y260492D02*
Y265492D01*
X147381Y264492D01*
G01Y260492D02*
X149381D01*
G01X153981Y265492D02*
X153381Y265392D01*
X152881Y264892D01*
X152481Y264392D01*
X152281Y263792D01*
X152181Y262992D01*
X152281Y262292D01*
X152481Y261592D01*
X152881Y261092D01*
X153381Y260692D01*
X153981Y260492D01*
X154681Y260692D01*
X155181Y261092D01*
X155481Y261592D01*
X155781Y262292D01*
X155881Y262992D01*
X155781Y263792D01*
X155481Y264392D01*
X155181Y264892D01*
X154681Y265392D01*
X153981Y265492D01*
G01X144881Y328777D02*
Y336577D01*
X157481D01*
Y328777D01*
X144881D01*
G01X148381Y330177D02*
Y335177D01*
X147381Y334177D01*
G01Y330177D02*
X149381D01*
G01X152181Y331177D02*
X152681Y330577D01*
X153381Y330277D01*
X154081Y330177D01*
X154781Y330277D01*
X155381Y330677D01*
X155881Y331177D01*
Y331677D01*
X155781Y332277D01*
X155181Y332677D01*
X154581Y332877D01*
X153881D01*
G01X154581D02*
X155081Y333077D01*
X155481Y333577D01*
X155681Y334077D01*
X155481Y334577D01*
X155081Y334977D01*
X154381Y335177D01*
X153581Y335077D01*
X152881Y334777D01*
G01X144881Y398462D02*
Y406262D01*
X157481D01*
Y398462D01*
X144881D01*
G01X148381Y399862D02*
Y404862D01*
X147381Y403862D01*
G01Y399862D02*
X149381D01*
G01X152381Y401962D02*
X152981Y402562D01*
X153481Y402862D01*
X154181Y403062D01*
X154781Y402862D01*
X155181Y402562D01*
X155481Y402062D01*
X155581Y401462D01*
X155481Y400962D01*
X155181Y400462D01*
X154681Y400062D01*
X154081Y399862D01*
X153381Y400062D01*
X152881Y400562D01*
X152481Y401262D01*
X152381Y402162D01*
X152581Y403262D01*
X152881Y403762D01*
X153281Y404362D01*
X153881Y404762D01*
X154381Y404862D01*
X154981Y404762D01*
X155381Y404262D01*
G01X144881Y468147D02*
Y475947D01*
X157481D01*
Y468147D01*
X144881D01*
G01X148381Y469547D02*
Y474547D01*
X147381Y473547D01*
G01Y469547D02*
X149381D01*
G01X152581Y470147D02*
X153181Y469747D01*
X153881Y469547D01*
X154481Y469747D01*
X155081Y470247D01*
X155481Y470947D01*
X155681Y471747D01*
Y472647D01*
X155481Y473447D01*
X155081Y474047D01*
X154581Y474447D01*
X153981Y474547D01*
X153381Y474447D01*
X152881Y474047D01*
X152481Y473547D01*
X152381Y472947D01*
X152481Y472347D01*
X152881Y471747D01*
X153381Y471447D01*
X153981Y471347D01*
X154681Y471447D01*
X155181Y471947D01*
X155681Y472647D01*
G01X144881Y537832D02*
Y545632D01*
X157481D01*
Y537832D01*
X144881D01*
G01X146781Y543432D02*
X147281Y543932D01*
X147881Y544132D01*
X148581Y544232D01*
X149381Y544132D01*
X149981Y543632D01*
X150181Y543132D01*
X150081Y542632D01*
X149781Y542232D01*
X148081Y541432D01*
X147281Y540832D01*
X146781Y540032D01*
X146681Y539232D01*
X150181D01*
G01X152381Y543432D02*
X152881Y543932D01*
X153481Y544132D01*
X154181Y544232D01*
X154981Y544132D01*
X155581Y543632D01*
X155781Y543132D01*
X155681Y542632D01*
X155381Y542232D01*
X153681Y541432D01*
X152881Y540832D01*
X152381Y540032D01*
X152281Y539232D01*
X155781D01*
G01X144881Y607517D02*
Y615317D01*
X157481D01*
Y607517D01*
X144881D01*
G01X146781Y613117D02*
X147281Y613617D01*
X147881Y613817D01*
X148581Y613917D01*
X149381Y613817D01*
X149981Y613317D01*
X150181Y612817D01*
X150081Y612317D01*
X149781Y611917D01*
X148081Y611117D01*
X147281Y610517D01*
X146781Y609717D01*
X146681Y608917D01*
X150181D01*
G01X152181Y609717D02*
X152681Y609317D01*
X153281Y609017D01*
X153981Y608917D01*
X154781Y609117D01*
X155381Y609417D01*
X155781Y610017D01*
X155881Y610717D01*
X155681Y611317D01*
X155281Y611817D01*
X154681Y612117D01*
X154081Y612217D01*
X153481Y612117D01*
X152781Y611817D01*
X152981Y613917D01*
X155281D01*
G01X144881Y677202D02*
Y685002D01*
X157481D01*
Y677202D01*
X144881D01*
G01X146781Y682802D02*
X147281Y683302D01*
X147881Y683502D01*
X148581Y683602D01*
X149381Y683502D01*
X149981Y683002D01*
X150181Y682502D01*
X150081Y682002D01*
X149781Y681602D01*
X148081Y680802D01*
X147281Y680202D01*
X146781Y679402D01*
X146681Y678602D01*
X150181D01*
G01X153981D02*
X154581Y678702D01*
X155281Y679002D01*
X155681Y679402D01*
X155881Y680002D01*
X155681Y680502D01*
X155181Y681002D01*
X154381Y681302D01*
X153581D01*
X153081Y681502D01*
X152681Y681902D01*
X152481Y682502D01*
X152781Y683002D01*
X153381Y683502D01*
X153981Y683602D01*
X154681Y683502D01*
X155281Y683002D01*
X155481Y682502D01*
X155381Y681902D01*
X154881Y681502D01*
X154381Y681302D01*
X153581D01*
X152881Y681002D01*
X152381Y680502D01*
X152181Y680002D01*
X152381Y679402D01*
X152781Y679002D01*
X153381Y678702D01*
X153981Y678602D01*
G01X270914Y-17728D02*
X271314Y-18195D01*
X271848Y-18461D01*
X272448Y-18528D01*
X272981Y-18461D01*
X273514Y-18128D01*
X273848Y-17728D01*
X273914Y-17328D01*
X273781Y-16861D01*
X273314Y-16528D01*
X272848Y-16395D01*
X272248D01*
G01X272848D02*
X273248Y-16195D01*
X273581Y-15861D01*
X273714Y-15461D01*
X273581Y-15061D01*
X273248Y-14728D01*
X272648Y-14528D01*
X272048Y-14595D01*
X271448Y-14861D01*
G01X239619Y-15195D02*
X240019Y-14795D01*
X240486Y-14595D01*
X241019Y-14528D01*
X241686Y-14661D01*
X242153Y-14995D01*
X242286Y-15395D01*
X242219Y-15795D01*
X241953Y-16128D01*
X240619Y-16795D01*
X240019Y-17261D01*
X239619Y-17928D01*
X239486Y-18528D01*
X242286D01*
G01X209391D02*
Y-14528D01*
X208591Y-15328D01*
G01Y-18528D02*
X210191D01*
G01X333905Y-17928D02*
X334305Y-18261D01*
X334772Y-18461D01*
X335372Y-18528D01*
X335972Y-18395D01*
X336439Y-18128D01*
X336772Y-17661D01*
X336839Y-17128D01*
X336705Y-16595D01*
X336372Y-16261D01*
X335905Y-15995D01*
X335439Y-15928D01*
X334972Y-15995D01*
X334372Y-16261D01*
X334572Y-14528D01*
X336372D01*
G01X304676Y-18528D02*
Y-14528D01*
X302209Y-17395D01*
X305543D01*
G01X329921Y50037D02*
Y57837D01*
X342521D01*
Y50037D01*
X329921D01*
G01X333421Y56437D02*
X332821Y56337D01*
X332321Y55837D01*
X331921Y55337D01*
X331721Y54737D01*
X331621Y53937D01*
X331721Y53237D01*
X331921Y52537D01*
X332321Y52037D01*
X332821Y51637D01*
X333421Y51437D01*
X334121Y51637D01*
X334621Y52037D01*
X334921Y52537D01*
X335221Y53237D01*
X335321Y53937D01*
X335221Y54737D01*
X334921Y55337D01*
X334621Y55837D01*
X334121Y56337D01*
X333421Y56437D01*
G01X337421Y55637D02*
X337921Y56137D01*
X338521Y56337D01*
X339221Y56437D01*
X340021Y56337D01*
X340621Y55837D01*
X340821Y55337D01*
X340721Y54837D01*
X340421Y54437D01*
X338721Y53637D01*
X337921Y53037D01*
X337421Y52237D01*
X337321Y51437D01*
X340821D01*
G01X329921Y119722D02*
Y127522D01*
X342521D01*
Y119722D01*
X329921D01*
G01X333421Y126122D02*
X332821Y126022D01*
X332321Y125522D01*
X331921Y125022D01*
X331721Y124422D01*
X331621Y123622D01*
X331721Y122922D01*
X331921Y122222D01*
X332321Y121722D01*
X332821Y121322D01*
X333421Y121122D01*
X334121Y121322D01*
X334621Y121722D01*
X334921Y122222D01*
X335221Y122922D01*
X335321Y123622D01*
X335221Y124422D01*
X334921Y125022D01*
X334621Y125522D01*
X334121Y126022D01*
X333421Y126122D01*
G01X337221Y121922D02*
X337721Y121522D01*
X338321Y121222D01*
X339021Y121122D01*
X339821Y121322D01*
X340421Y121622D01*
X340821Y122222D01*
X340921Y122922D01*
X340721Y123522D01*
X340321Y124022D01*
X339721Y124322D01*
X339121Y124422D01*
X338521Y124322D01*
X337821Y124022D01*
X338021Y126122D01*
X340321D01*
G01X329921Y189407D02*
Y197207D01*
X342521D01*
Y189407D01*
X329921D01*
G01X333421Y195807D02*
X332821Y195707D01*
X332321Y195207D01*
X331921Y194707D01*
X331721Y194107D01*
X331621Y193307D01*
X331721Y192607D01*
X331921Y191907D01*
X332321Y191407D01*
X332821Y191007D01*
X333421Y190807D01*
X334121Y191007D01*
X334621Y191407D01*
X334921Y191907D01*
X335221Y192607D01*
X335321Y193307D01*
X335221Y194107D01*
X334921Y194707D01*
X334621Y195207D01*
X334121Y195707D01*
X333421Y195807D01*
G01X339021Y190807D02*
X339621Y190907D01*
X340321Y191207D01*
X340721Y191607D01*
X340921Y192207D01*
X340721Y192707D01*
X340221Y193207D01*
X339421Y193507D01*
X338621D01*
X338121Y193707D01*
X337721Y194107D01*
X337521Y194707D01*
X337821Y195207D01*
X338421Y195707D01*
X339021Y195807D01*
X339721Y195707D01*
X340321Y195207D01*
X340521Y194707D01*
X340421Y194107D01*
X339921Y193707D01*
X339421Y193507D01*
X338621D01*
X337921Y193207D01*
X337421Y192707D01*
X337221Y192207D01*
X337421Y191607D01*
X337821Y191207D01*
X338421Y190907D01*
X339021Y190807D01*
G01X329921Y259092D02*
Y266892D01*
X342521D01*
Y259092D01*
X329921D01*
G01X333421Y260492D02*
Y265492D01*
X332421Y264492D01*
G01Y260492D02*
X334421D01*
G01X339021D02*
Y265492D01*
X338021Y264492D01*
G01Y260492D02*
X340021D01*
G01X329921Y328777D02*
Y336577D01*
X342521D01*
Y328777D01*
X329921D01*
G01X333421Y330177D02*
Y335177D01*
X332421Y334177D01*
G01Y330177D02*
X334421D01*
G01X340021D02*
Y335177D01*
X336921Y331577D01*
X341121D01*
G01X329921Y398462D02*
Y406262D01*
X342521D01*
Y398462D01*
X329921D01*
G01X333421Y399862D02*
Y404862D01*
X332421Y403862D01*
G01Y399862D02*
X334421D01*
G01X338921D02*
X339021Y400962D01*
X339621Y402762D01*
X340021Y403662D01*
X340721Y404862D01*
X337421D01*
G01X329921Y468147D02*
Y475947D01*
X342521D01*
Y468147D01*
X329921D01*
G01X331821Y473747D02*
X332321Y474247D01*
X332921Y474447D01*
X333621Y474547D01*
X334421Y474447D01*
X335021Y473947D01*
X335221Y473447D01*
X335121Y472947D01*
X334821Y472547D01*
X333121Y471747D01*
X332321Y471147D01*
X331821Y470347D01*
X331721Y469547D01*
X335221D01*
G01X339021Y474547D02*
X338421Y474447D01*
X337921Y473947D01*
X337521Y473447D01*
X337321Y472847D01*
X337221Y472047D01*
X337321Y471347D01*
X337521Y470647D01*
X337921Y470147D01*
X338421Y469747D01*
X339021Y469547D01*
X339721Y469747D01*
X340221Y470147D01*
X340521Y470647D01*
X340821Y471347D01*
X340921Y472047D01*
X340821Y472847D01*
X340521Y473447D01*
X340221Y473947D01*
X339721Y474447D01*
X339021Y474547D01*
G01X329921Y537832D02*
Y545632D01*
X342521D01*
Y537832D01*
X329921D01*
G01X331821Y543432D02*
X332321Y543932D01*
X332921Y544132D01*
X333621Y544232D01*
X334421Y544132D01*
X335021Y543632D01*
X335221Y543132D01*
X335121Y542632D01*
X334821Y542232D01*
X333121Y541432D01*
X332321Y540832D01*
X331821Y540032D01*
X331721Y539232D01*
X335221D01*
G01X337221Y540232D02*
X337721Y539632D01*
X338421Y539332D01*
X339121Y539232D01*
X339821Y539332D01*
X340421Y539732D01*
X340921Y540232D01*
Y540732D01*
X340821Y541332D01*
X340221Y541732D01*
X339621Y541932D01*
X338921D01*
G01X339621D02*
X340121Y542132D01*
X340521Y542632D01*
X340721Y543132D01*
X340521Y543632D01*
X340121Y544032D01*
X339421Y544232D01*
X338621Y544132D01*
X337921Y543832D01*
G01X329921Y607517D02*
Y615317D01*
X342521D01*
Y607517D01*
X329921D01*
G01X331821Y613117D02*
X332321Y613617D01*
X332921Y613817D01*
X333621Y613917D01*
X334421Y613817D01*
X335021Y613317D01*
X335221Y612817D01*
X335121Y612317D01*
X334821Y611917D01*
X333121Y611117D01*
X332321Y610517D01*
X331821Y609717D01*
X331721Y608917D01*
X335221D01*
G01X337421Y611017D02*
X338021Y611617D01*
X338521Y611917D01*
X339221Y612117D01*
X339821Y611917D01*
X340221Y611617D01*
X340521Y611117D01*
X340621Y610517D01*
X340521Y610017D01*
X340221Y609517D01*
X339721Y609117D01*
X339121Y608917D01*
X338421Y609117D01*
X337921Y609617D01*
X337521Y610317D01*
X337421Y611217D01*
X337621Y612317D01*
X337921Y612817D01*
X338321Y613417D01*
X338921Y613817D01*
X339421Y613917D01*
X340021Y613817D01*
X340421Y613317D01*
G01X329921Y677202D02*
Y685002D01*
X342521D01*
Y677202D01*
X329921D01*
G01X331821Y682802D02*
X332321Y683302D01*
X332921Y683502D01*
X333621Y683602D01*
X334421Y683502D01*
X335021Y683002D01*
X335221Y682502D01*
X335121Y682002D01*
X334821Y681602D01*
X333121Y680802D01*
X332321Y680202D01*
X331821Y679402D01*
X331721Y678602D01*
X335221D01*
G01X337621Y679202D02*
X338221Y678802D01*
X338921Y678602D01*
X339521Y678802D01*
X340121Y679302D01*
X340521Y680002D01*
X340721Y680802D01*
Y681702D01*
X340521Y682502D01*
X340121Y683102D01*
X339621Y683502D01*
X339021Y683602D01*
X338421Y683502D01*
X337921Y683102D01*
X337521Y682602D01*
X337421Y682002D01*
X337521Y681402D01*
X337921Y680802D01*
X338421Y680502D01*
X339021Y680402D01*
X339721Y680502D01*
X340221Y681002D01*
X340721Y681702D01*
G01X365600Y-16861D02*
X366067Y-16395D01*
X366467Y-16128D01*
X367000Y-15995D01*
X367467Y-16128D01*
X367800Y-16395D01*
X368067Y-16795D01*
X368134Y-17261D01*
X368067Y-17661D01*
X367800Y-18061D01*
X367400Y-18395D01*
X366934Y-18528D01*
X366400Y-18395D01*
X365934Y-17995D01*
X365667Y-17395D01*
X365600Y-16728D01*
X365734Y-15861D01*
X365934Y-15395D01*
X366267Y-14928D01*
X366734Y-14595D01*
X367200Y-14528D01*
X367667Y-14661D01*
X368000Y-14995D01*
G01X514960Y50037D02*
Y57837D01*
X527560D01*
Y50037D01*
X514960D01*
G01X518460Y56437D02*
X517860Y56337D01*
X517360Y55837D01*
X516960Y55337D01*
X516760Y54737D01*
X516660Y53937D01*
X516760Y53237D01*
X516960Y52537D01*
X517360Y52037D01*
X517860Y51637D01*
X518460Y51437D01*
X519160Y51637D01*
X519660Y52037D01*
X519960Y52537D01*
X520260Y53237D01*
X520360Y53937D01*
X520260Y54737D01*
X519960Y55337D01*
X519660Y55837D01*
X519160Y56337D01*
X518460Y56437D01*
G01X522260Y52437D02*
X522760Y51837D01*
X523460Y51537D01*
X524160Y51437D01*
X524860Y51537D01*
X525460Y51937D01*
X525960Y52437D01*
Y52937D01*
X525860Y53537D01*
X525260Y53937D01*
X524660Y54137D01*
X523960D01*
G01X524660D02*
X525160Y54337D01*
X525560Y54837D01*
X525760Y55337D01*
X525560Y55837D01*
X525160Y56237D01*
X524460Y56437D01*
X523660Y56337D01*
X522960Y56037D01*
G01X514960Y119722D02*
Y127522D01*
X527560D01*
Y119722D01*
X514960D01*
G01X518460Y126122D02*
X517860Y126022D01*
X517360Y125522D01*
X516960Y125022D01*
X516760Y124422D01*
X516660Y123622D01*
X516760Y122922D01*
X516960Y122222D01*
X517360Y121722D01*
X517860Y121322D01*
X518460Y121122D01*
X519160Y121322D01*
X519660Y121722D01*
X519960Y122222D01*
X520260Y122922D01*
X520360Y123622D01*
X520260Y124422D01*
X519960Y125022D01*
X519660Y125522D01*
X519160Y126022D01*
X518460Y126122D01*
G01X522460Y123222D02*
X523060Y123822D01*
X523560Y124122D01*
X524260Y124322D01*
X524860Y124122D01*
X525260Y123822D01*
X525560Y123322D01*
X525660Y122722D01*
X525560Y122222D01*
X525260Y121722D01*
X524760Y121322D01*
X524160Y121122D01*
X523460Y121322D01*
X522960Y121822D01*
X522560Y122522D01*
X522460Y123422D01*
X522660Y124522D01*
X522960Y125022D01*
X523360Y125622D01*
X523960Y126022D01*
X524460Y126122D01*
X525060Y126022D01*
X525460Y125522D01*
G01X514960Y189407D02*
Y197207D01*
X527560D01*
Y189407D01*
X514960D01*
G01X518460Y195807D02*
X517860Y195707D01*
X517360Y195207D01*
X516960Y194707D01*
X516760Y194107D01*
X516660Y193307D01*
X516760Y192607D01*
X516960Y191907D01*
X517360Y191407D01*
X517860Y191007D01*
X518460Y190807D01*
X519160Y191007D01*
X519660Y191407D01*
X519960Y191907D01*
X520260Y192607D01*
X520360Y193307D01*
X520260Y194107D01*
X519960Y194707D01*
X519660Y195207D01*
X519160Y195707D01*
X518460Y195807D01*
G01X522660Y191407D02*
X523260Y191007D01*
X523960Y190807D01*
X524560Y191007D01*
X525160Y191507D01*
X525560Y192207D01*
X525760Y193007D01*
Y193907D01*
X525560Y194707D01*
X525160Y195307D01*
X524660Y195707D01*
X524060Y195807D01*
X523460Y195707D01*
X522960Y195307D01*
X522560Y194807D01*
X522460Y194207D01*
X522560Y193607D01*
X522960Y193007D01*
X523460Y192707D01*
X524060Y192607D01*
X524760Y192707D01*
X525260Y193207D01*
X525760Y193907D01*
G01X514960Y259092D02*
Y266892D01*
X527560D01*
Y259092D01*
X514960D01*
G01X518460Y260492D02*
Y265492D01*
X517460Y264492D01*
G01Y260492D02*
X519460D01*
G01X522460Y264692D02*
X522960Y265192D01*
X523560Y265392D01*
X524260Y265492D01*
X525060Y265392D01*
X525660Y264892D01*
X525860Y264392D01*
X525760Y263892D01*
X525460Y263492D01*
X523760Y262692D01*
X522960Y262092D01*
X522460Y261292D01*
X522360Y260492D01*
X525860D01*
G01X514960Y328777D02*
Y336577D01*
X527560D01*
Y328777D01*
X514960D01*
G01X518460Y330177D02*
Y335177D01*
X517460Y334177D01*
G01Y330177D02*
X519460D01*
G01X522260Y330977D02*
X522760Y330577D01*
X523360Y330277D01*
X524060Y330177D01*
X524860Y330377D01*
X525460Y330677D01*
X525860Y331277D01*
X525960Y331977D01*
X525760Y332577D01*
X525360Y333077D01*
X524760Y333377D01*
X524160Y333477D01*
X523560Y333377D01*
X522860Y333077D01*
X523060Y335177D01*
X525360D01*
G01X514960Y398462D02*
Y406262D01*
X527560D01*
Y398462D01*
X514960D01*
G01X518460Y399862D02*
Y404862D01*
X517460Y403862D01*
G01Y399862D02*
X519460D01*
G01X524060D02*
X524660Y399962D01*
X525360Y400262D01*
X525760Y400662D01*
X525960Y401262D01*
X525760Y401762D01*
X525260Y402262D01*
X524460Y402562D01*
X523660D01*
X523160Y402762D01*
X522760Y403162D01*
X522560Y403762D01*
X522860Y404262D01*
X523460Y404762D01*
X524060Y404862D01*
X524760Y404762D01*
X525360Y404262D01*
X525560Y403762D01*
X525460Y403162D01*
X524960Y402762D01*
X524460Y402562D01*
X523660D01*
X522960Y402262D01*
X522460Y401762D01*
X522260Y401262D01*
X522460Y400662D01*
X522860Y400262D01*
X523460Y399962D01*
X524060Y399862D01*
G01X514960Y468147D02*
Y475947D01*
X527560D01*
Y468147D01*
X514960D01*
G01X516860Y473747D02*
X517360Y474247D01*
X517960Y474447D01*
X518660Y474547D01*
X519460Y474447D01*
X520060Y473947D01*
X520260Y473447D01*
X520160Y472947D01*
X519860Y472547D01*
X518160Y471747D01*
X517360Y471147D01*
X516860Y470347D01*
X516760Y469547D01*
X520260D01*
G01X524060D02*
Y474547D01*
X523060Y473547D01*
G01Y469547D02*
X525060D01*
G01X514960Y537832D02*
Y545632D01*
X527560D01*
Y537832D01*
X514960D01*
G01X516860Y543432D02*
X517360Y543932D01*
X517960Y544132D01*
X518660Y544232D01*
X519460Y544132D01*
X520060Y543632D01*
X520260Y543132D01*
X520160Y542632D01*
X519860Y542232D01*
X518160Y541432D01*
X517360Y540832D01*
X516860Y540032D01*
X516760Y539232D01*
X520260D01*
G01X525060D02*
Y544232D01*
X521960Y540632D01*
X526160D01*
G01X514960Y607517D02*
Y615317D01*
X527560D01*
Y607517D01*
X514960D01*
G01X516860Y613117D02*
X517360Y613617D01*
X517960Y613817D01*
X518660Y613917D01*
X519460Y613817D01*
X520060Y613317D01*
X520260Y612817D01*
X520160Y612317D01*
X519860Y611917D01*
X518160Y611117D01*
X517360Y610517D01*
X516860Y609717D01*
X516760Y608917D01*
X520260D01*
G01X523960D02*
X524060Y610017D01*
X524660Y611817D01*
X525060Y612717D01*
X525760Y613917D01*
X522460D01*
G01X514960Y677202D02*
Y685002D01*
X527560D01*
Y677202D01*
X514960D01*
G01X516660Y679602D02*
X517160Y679002D01*
X517860Y678702D01*
X518560Y678602D01*
X519260Y678702D01*
X519860Y679102D01*
X520360Y679602D01*
Y680102D01*
X520260Y680702D01*
X519660Y681102D01*
X519060Y681302D01*
X518360D01*
G01X519060D02*
X519560Y681502D01*
X519960Y682002D01*
X520160Y682502D01*
X519960Y683002D01*
X519560Y683402D01*
X518860Y683602D01*
X518060Y683502D01*
X517360Y683202D01*
G01X524060Y683602D02*
X523460Y683502D01*
X522960Y683002D01*
X522560Y682502D01*
X522360Y681902D01*
X522260Y681102D01*
X522360Y680402D01*
X522560Y679702D01*
X522960Y679202D01*
X523460Y678802D01*
X524060Y678602D01*
X524760Y678802D01*
X525260Y679202D01*
X525560Y679702D01*
X525860Y680402D01*
X525960Y681102D01*
X525860Y681902D01*
X525560Y682502D01*
X525260Y683002D01*
X524760Y683502D01*
X524060Y683602D01*
M02*
